# T6G (Grand Teton) — schematic parts with pin connectivity, parts 8082–8082 of 8303; source: Cadence DE-HDL packaged netlist (pstxprt.dat, pstxnet.dat, pstchip.dat)

U26  GENOA_SP5  SOCKET6096_13568-001 IO  pkg SOCKET6096_93-4X120-45XA  page 37  (pins 1009-1344 of 6096)
  AP18  MJA_CHECK5  BI  = M_J_CPU1_SA_CB<5>
  AP19  VSS_AP19  POWER  = GND
  AP20  MIA_CHECK6  BI  = M_I_CPU1_SA_CB<6>
  AP21  MIA_CHECK5  BI  = M_I_CPU1_SA_CB<5>
  AP22  VSS_AP22  POWER  = GND
  AP23  VDDCR_CPU0_AP23  POWER  = PVDDCR_CPU0_P1
  AP24  VDDCR_CPU0_AP24  POWER  = PVDDCR_CPU0_P1
  AP25  VSS_AP25  POWER  = GND
  AP26  VDDCR_CPU0_AP26  POWER  = PVDDCR_CPU0_P1
  AP27  VDDCR_CPU0_AP27  POWER  = PVDDCR_CPU0_P1
  AP28  VSS_AP28  POWER  = GND
  AP29  VDDCR_CPU0_AP29  POWER  = PVDDCR_CPU0_P1
  AP30  VDDCR_CPU0_AP30  POWER  = PVDDCR_CPU0_P1
  AP31  VSS_AP31  POWER  = GND
  AP32  VDDCR_CPU0_AP32  POWER  = PVDDCR_CPU0_P1
  AP33  VDDCR_CPU0_AP33  POWER  = PVDDCR_CPU0_P1
  AP34  VSS_AP34  POWER  = GND
  AP35  \g3_rxn15||sata37_rxn\  IN  = GMI_CPU0_G1_CPU1_G3_TX_DN<0>
  AP36  \g3_rxp15||sata37_rxp\  IN  = GMI_CPU0_G1_CPU1_G3_TX_DP<0>
  AP37  VSS_AP37  POWER  = GND
  AP39  VSS_AP39  POWER  = GND
  AP40  G1_TXP0  OUT  = P5E_CPU1_G1_TX_DP<0>
  AP41  G1_TXN0  OUT  = P5E_CPU1_G1_TX_DN<0>
  AP42  VSS_AP42  POWER  = GND
  AP43  VDDCR_CPU0_AP43  POWER  = PVDDCR_CPU0_P1
  AP44  VDDCR_CPU0_AP44  POWER  = PVDDCR_CPU0_P1
  AP45  VSS_AP45  POWER  = GND
  AP46  VDDCR_CPU0_AP46  POWER  = PVDDCR_CPU0_P1
  AP47  VDDCR_CPU0_AP47  POWER  = PVDDCR_CPU0_P1
  AP48  VSS_AP48  POWER  = GND
  AP49  VDDCR_CPU0_AP49  POWER  = PVDDCR_CPU0_P1
  AP50  VDDCR_CPU0_AP50  POWER  = PVDDCR_CPU0_P1
  AP51  VSS_AP51  POWER  = GND
  AP52  VDDCR_CPU0_AP52  POWER  = PVDDCR_CPU0_P1
  AP53  VDDCR_CPU0_AP53  POWER  = PVDDCR_CPU0_P1
  AP54  VSS_AP54  POWER  = GND
  AP55  MCA_CHECK5  BI  = M_C_CPU1_SA_CB<5>
  AP56  MCA_CHECK6  BI  = M_C_CPU1_SA_CB<6>
  AP57  VSS_AP57  POWER  = GND
  AP58  MDA_CHECK5  BI  = M_D_CPU1_SA_CB<5>
  AP59  VSS_AP59  POWER  = GND
  AP60  MDA_CHECK6  BI  = M_D_CPU1_SA_CB<6>
  AP61  VSS_AP61  POWER  = GND
  AP62  MBA_CHECK5  BI  = M_B_CPU1_SA_CB<5>
  AP63  MBA_CHECK6  BI  = M_B_CPU1_SA_CB<6>
  AP64  VSS_AP64  POWER  = GND
  AP65  MFA_CHECK5  BI  = M_F_CPU1_SA_CB<5>
  AP66  VSS_AP66  POWER  = GND
  AP67  MFA_CHECK6  BI  = M_F_CPU1_SA_CB<6>
  AP68  VSS_AP68  POWER  = GND
  AP69  MEA_CHECK5  BI  = M_E_CPU1_SA_CB<5>
  AP70  MEA_CHECK6  BI  = M_E_CPU1_SA_CB<6>
  AP71  VSS_AP71  POWER  = GND
  AP72  MAA_CHECK5  BI  = M_A_CPU1_SA_CB<5>
  AP73  VSS_AP73  POWER  = GND
  AP74  MAA_CHECK6  BI  = M_A_CPU1_SA_CB<6>
  AR1  VSS_AR1  POWER  = GND
  AR2  MG_ALERT_L  IN  = M_G_CPU1_ALERT_R_N
  AR3  MGA_CHECK7  BI  = M_G_CPU1_SA_CB<7>
  AR4  VDDCR_SOC_AR4  POWER  = PVDDCR_SOC_P1
  AR5  VSS_AR5  POWER  = GND
  AR6  VSS_AR6  POWER  = GND
  AR7  MKA_CHECK7  BI  = M_K_CPU1_SA_CB<7>
  AR8  VSS_AR8  POWER  = GND
  AR9  VSS_AR9  POWER  = GND
  AR10  MLA_CHECK7  BI  = M_L_CPU1_SA_CB<7>
  AR11  VDDCR_SOC_AR11  POWER  = PVDDCR_SOC_P1
  AR12  VSS_AR12  POWER  = GND
  AR13  VSS_AR13  POWER  = GND
  AR14  MHA_CHECK7  BI  = M_H_CPU1_SA_CB<7>
  AR15  VSS_AR15  POWER  = GND
  AR16  VSS_AR16  POWER  = GND
  AR17  MJA_CHECK7  BI  = M_J_CPU1_SA_CB<7>
  AR18  VDDCR_SOC_AR18  POWER  = PVDDCR_SOC_P1
  AR19  VSS_AR19  POWER  = GND
  AR20  VSS_AR20  POWER  = GND
  AR21  MIA_CHECK7  BI  = M_I_CPU1_SA_CB<7>
  AR22  VSS_AR22  POWER  = GND
  AR23  VDDCR_CPU0_AR23  POWER  = PVDDCR_CPU0_P1
  AR24  VSS_AR24  POWER  = GND
  AR25  VDDCR_CPU0_AR25  POWER  = PVDDCR_CPU0_P1
  AR26  VSS_AR26  POWER  = GND
  AR27  VDDCR_CPU0_AR27  POWER  = PVDDCR_CPU0_P1
  AR28  VSS_AR28  POWER  = GND
  AR29  VDDCR_CPU0_AR29  POWER  = PVDDCR_CPU0_P1
  AR30  VSS_AR30  POWER  = GND
  AR31  VDDCR_CPU0_AR31  POWER  = PVDDCR_CPU0_P1
  AR32  VSS_AR32  POWER  = GND
  AR33  VDDCR_CPU0_AR33  POWER  = PVDDCR_CPU0_P1
  AR34  VSS_AR34  POWER  = GND
  AR35  VDDCR_CPU0_AR35  POWER  = PVDDCR_CPU0_P1
  AR36  VSS_AR36  POWER  = GND
  AR40  VDDCR_CPU0_AR40  POWER  = PVDDCR_CPU0_P1
  AR41  VSS_AR41  POWER  = GND
  AR42  VDDCR_CPU0_AR42  POWER  = PVDDCR_CPU0_P1
  AR43  VSS_AR43  POWER  = GND
  AR44  VDDCR_CPU0_AR44  POWER  = PVDDCR_CPU0_P1
  AR45  VSS_AR45  POWER  = GND
  AR46  VDDCR_CPU0_AR46  POWER  = PVDDCR_CPU0_P1
  AR47  VSS_AR47  POWER  = GND
  AR48  VDDCR_CPU0_AR48  POWER  = PVDDCR_CPU0_P1
  AR49  VSS_AR49  POWER  = GND
  AR50  VDDCR_CPU0_AR50  POWER  = PVDDCR_CPU0_P1
  AR51  VSS_AR51  POWER  = GND
  AR52  VDD_18_S5_AR52  POWER  = PVDD18_S5_P1
  AR53  VSS_AR53  POWER  = GND
  AR54  VDD_18_S5_AR54  POWER  = PVDD18_S5_P1
  AR55  MCA_CHECK7  BI  = M_C_CPU1_SA_CB<7>
  AR56  VSS_AR56  POWER  = GND
  AR57  VSS_AR57  POWER  = GND
  AR58  VDDIO_AR58  POWER  = PVDDIO_P1
  AR59  MDA_CHECK7  BI  = M_D_CPU1_SA_CB<7>
  AR60  VSS_AR60  POWER  = GND
  AR61  VSS_AR61  POWER  = GND
  AR62  MBA_CHECK7  BI  = M_B_CPU1_SA_CB<7>
  AR63  VSS_AR63  POWER  = GND
  AR64  VSS_AR64  POWER  = GND
  AR65  VDDIO_AR65  POWER  = PVDDIO_P1
  AR66  MFA_CHECK7  BI  = M_F_CPU1_SA_CB<7>
  AR67  VSS_AR67  POWER  = GND
  AR68  VSS_AR68  POWER  = GND
  AR69  MEA_CHECK7  BI  = M_E_CPU1_SA_CB<7>
  AR70  VSS_AR70  POWER  = GND
  AR71  VSS_AR71  POWER  = GND
  AR72  VDDIO_AR72  POWER  = PVDDIO_P1
  AR73  MAA_CHECK7  BI  = M_A_CPU1_SA_CB<7>
  AR74  MA_ALERT_L  IN  = M_A_CPU1_ALERT_R_N
  AR75  VSS_AR75  POWER  = GND
  AT2  MG_RESET_L  OUT  = M_G_CPU1_RESET_N
  AT3  VSS_AT3  POWER  = GND
  AT4  VSS_AT4  POWER  = GND
  AT5  VSS_AT5  POWER  = GND
  AT6  VSS_AT6  POWER  = GND
  AT7  MK_ALERT_L  IN  = M_K_CPU1_ALERT_R_N
  AT8  VSS_AT8  POWER  = GND
  AT9  VSS_AT9  POWER  = GND
  AT10  VSS_AT10  POWER  = GND
  AT11  ML_ALERT_L  IN  = M_L_CPU1_ALERT_R_N
  AT12  VSS_AT12  POWER  = GND
  AT13  VSS_AT13  POWER  = GND
  AT14  MH_ALERT_L  IN  = M_H_CPU1_ALERT_R_N
  AT15  VSS_AT15  POWER  = GND
  AT16  VSS_AT16  POWER  = GND
  AT17  VSS_AT17  POWER  = GND
  AT18  MJ_ALERT_L  IN  = M_J_CPU1_ALERT_R_N
  AT19  VSS_AT19  POWER  = GND
  AT20  VSS_AT20  POWER  = GND
  AT21  MI_ALERT_L  IN  = M_I_CPU1_ALERT_R_N
  AT22  VDDCR_SOC_AT22  POWER  = PVDDCR_SOC_P1
  AT23  VSS_AT23  POWER  = GND
  AT24  VDDCR_CPU0_AT24  POWER  = PVDDCR_CPU0_P1
  AT25  VSS_AT25  POWER  = GND
  AT26  VDDCR_CPU0_AT26  POWER  = PVDDCR_CPU0_P1
  AT27  VSS_AT27  POWER  = GND
  AT28  VDDCR_CPU0_AT28  POWER  = PVDDCR_CPU0_P1
  AT29  VSS_AT29  POWER  = GND
  AT30  VDDCR_CPU0_AT30  POWER  = PVDDCR_CPU0_P1
  AT31  VSS_AT31  POWER  = GND
  AT32  VDDCR_CPU0_AT32  POWER  = PVDDCR_CPU0_P1
  AT33  VSS_AT33  POWER  = GND
  AT34  VDDCR_CPU0_AT34  POWER  = PVDDCR_CPU0_P1
  AT35  VSS_AT35  POWER  = GND
  AT36  VDDCR_CPU0_AT36  POWER  = PVDDCR_CPU0_P1
  AT37  VSS_AT37  POWER  = GND
  AT39  VDDCR_CPU0_AT39  POWER  = PVDDCR_CPU0_P1
  AT40  VSS_AT40  POWER  = GND
  AT41  VDDCR_CPU0_AT41  POWER  = PVDDCR_CPU0_P1
  AT42  VSS_AT42  POWER  = GND
  AT43  VDDCR_CPU0_AT43  POWER  = PVDDCR_CPU0_P1
  AT44  VSS_AT44  POWER  = GND
  AT45  VDDCR_CPU0_AT45  POWER  = PVDDCR_CPU0_P1
  AT46  VSS_AT46  POWER  = GND
  AT47  VDDCR_CPU0_AT47  POWER  = PVDDCR_CPU0_P1
  AT48  VSS_AT48  POWER  = GND
  AT49  VDDCR_CPU0_AT49  POWER  = PVDDCR_CPU0_P1
  AT50  VSS_AT50  POWER  = GND
  AT51  VDD_18_S5_AT51  POWER  = PVDD18_S5_P1
  AT52  VSS_AT52  POWER  = GND
  AT53  VDD_18_S5_AT53  POWER  = PVDD18_S5_P1
  AT54  VSS_AT54  POWER  = GND
  AT55  MC_ALERT_L  IN  = M_C_CPU1_ALERT_R_N
  AT56  VSS_AT56  POWER  = GND
  AT57  VSS_AT57  POWER  = GND
  AT58  MD_ALERT_L  IN  = M_D_CPU1_ALERT_R_N
  AT59  VSS_AT59  POWER  = GND
  AT60  VSS_AT60  POWER  = GND
  AT61  VSS_AT61  POWER  = GND
  AT62  MB_ALERT_L  IN  = M_B_CPU1_ALERT_R_N
  AT63  VSS_AT63  POWER  = GND
  AT64  VSS_AT64  POWER  = GND
  AT65  MF_ALERT_L  IN  = M_F_CPU1_ALERT_R_N
  AT66  VSS_AT66  POWER  = GND
  AT67  VSS_AT67  POWER  = GND
  AT68  VSS_AT68  POWER  = GND
  AT69  ME_ALERT_L  IN  = M_E_CPU1_ALERT_R_N
  AT70  VSS_AT70  POWER  = GND
  AT71  VSS_AT71  POWER  = GND
  AT72  VSS_AT72  POWER  = GND
  AT73  VSS_AT73  POWER  = GND
  AT74  MA_RESET_L  OUT  = M_A_CPU1_RESET_N
  AU1  VSS_AU1  POWER  = GND
  AU2  MGA0_CS_L0  OUT  = M_G_CPU1_SA_CS_N<0>
  AU3  VSS_AU3  POWER  = GND
  AU4  VSS_AU4  POWER  = GND
  AU5  MKA0_CS_L0  OUT  = M_K_CPU1_SA_CS_N<0>
  AU6  VSS_AU6  POWER  = GND
  AU7  MK_RESET_L  OUT  = M_K_CPU1_RESET_N
  AU8  VSS_AU8  POWER  = GND
  AU9  MLA0_CS_L0  OUT  = M_L_CPU1_SA_CS_N<0>
  AU10  ML_RESET_L  OUT  = M_L_CPU1_RESET_N
  AU11  VSS_AU11  POWER  = GND
  AU12  MHA0_CS_L0  OUT  = M_H_CPU1_SA_CS_N<0>
  AU13  VSS_AU13  POWER  = GND
  AU14  MH_RESET_L  OUT  = M_H_CPU1_RESET_N
  AU15  VSS_AU15  POWER  = GND
  AU16  MJA0_CS_L0  OUT  = M_J_CPU1_SA_CS_N<0>
  AU17  MJ_RESET_L  OUT  = M_J_CPU1_RESET_N
  AU18  VSS_AU18  POWER  = GND
  AU19  MIA0_CS_L0  OUT  = M_I_CPU1_SA_CS_N<0>
  AU20  VSS_AU20  POWER  = GND
  AU21  MI_RESET_L  OUT  = M_I_CPU1_RESET_N
  AU22  VSS_AU22  POWER  = GND
  AU23  VDDCR_SOC_AU23  POWER  = PVDDCR_SOC_P1
  AU24  VSS_AU24  POWER  = GND
  AU25  VDDCR_CPU0_AU25  POWER  = PVDDCR_CPU0_P1
  AU26  VSS_AU26  POWER  = GND
  AU27  VDDCR_SOC_AU27  POWER  = PVDDCR_SOC_P1
  AU28  VSS_AU28  POWER  = GND
  AU29  VDDCR_CPU0_AU29  POWER  = PVDDCR_CPU0_P1
  AU30  VSS_AU30  POWER  = GND
  AU31  VDDCR_SOC_AU31  POWER  = PVDDCR_SOC_P1
  AU32  VSS_AU32  POWER  = GND
  AU33  VDDCR_CPU0_AU33  POWER  = PVDDCR_CPU0_P1
  AU34  VSS_AU34  POWER  = GND
  AU35  VDDCR_SOC_AU35  POWER  = PVDDCR_SOC_P1
  AU36  VSS_AU36  POWER  = GND
  AU40  VDDCR_SOC_AU40  POWER  = PVDDCR_SOC_P1
  AU41  VSS_AU41  POWER  = GND
  AU42  VDDCR_CPU0_AU42  POWER  = PVDDCR_CPU0_P1
  AU43  VSS_AU43  POWER  = GND
  AU44  VDDCR_CPU0_AU44  POWER  = PVDDCR_CPU0_P1
  AU45  VSS_AU45  POWER  = GND
  AU46  VDDCR_CPU0_AU46  POWER  = PVDDCR_CPU0_P1
  AU47  VSS_AU47  POWER  = GND
  AU48  VDDCR_CPU0_AU48  POWER  = PVDDCR_CPU0_P1
  AU49  VSS_AU49  POWER  = GND
  AU50  VDD_18_S5_AU50  POWER  = PVDD18_S5_P1
  AU51  VSS_AU51  POWER  = GND
  AU52  VDD_18_S5_AU52  POWER  = PVDD18_S5_P1
  AU53  VSS_AU53  POWER  = GND
  AU54  VDD_18_S5_AU54  POWER  = PVDD18_S5_P1
  AU55  MC_RESET_L  OUT  = M_C_CPU1_RESET_N
  AU56  VSS_AU56  POWER  = GND
  AU57  MCA1_CS_L0  OUT  = NC
  AU58  VSS_AU58  POWER  = GND
  AU59  MD_RESET_L  OUT  = M_D_CPU1_RESET_N
  AU60  MDA1_CS_L0  OUT  = NC
  AU61  VSS_AU61  POWER  = GND
  AU62  MB_RESET_L  OUT  = M_B_CPU1_RESET_N
  AU63  VSS_AU63  POWER  = GND
  AU64  MBA1_CS_L0  OUT  = NC
  AU65  VSS_AU65  POWER  = GND
  AU66  MF_RESET_L  OUT  = M_F_CPU1_RESET_N
  AU67  MFA1_CS_L0  OUT  = NC
  AU68  VSS_AU68  POWER  = GND
  AU69  ME_RESET_L  OUT  = M_E_CPU1_RESET_N
  AU70  VSS_AU70  POWER  = GND
  AU71  MEA1_CS_L0  OUT  = NC
  AU72  VSS_AU72  POWER  = GND
  AU73  VSS_AU73  POWER  = GND
  AU74  MAA1_CS_L0  OUT  = NC
  AU75  VSS_AU75  POWER  = GND
  AV2  MGA1_CS_L0  OUT  = NC
  AV3  VSS_AV3  POWER  = GND
  AV4  MGA0_CS_L1  OUT  = M_G_CPU1_SA_CS_N<1>
  AV5  VDDCR_SOC_AV5  POWER  = PVDDCR_SOC_P1
  AV6  MKA1_CS_L0  OUT  = NC
  AV7  MKA0_CS_L1  OUT  = M_K_CPU1_SA_CS_N<1>
  AV8  VSS_AV8  POWER  = GND
  AV9  MLA1_CS_L0  OUT  = NC
  AV10  VSS_AV10  POWER  = GND
  AV11  MLA0_CS_L1  OUT  = M_L_CPU1_SA_CS_N<1>
  AV12  VDDCR_SOC_AV12  POWER  = PVDDCR_SOC_P1
  AV13  MHA1_CS_L0  OUT  = NC
  AV14  MHA0_CS_L1  OUT  = M_H_CPU1_SA_CS_N<1>
  AV15  VSS_AV15  POWER  = GND
  AV16  MJA1_CS_L0  OUT  = NC
  AV17  VSS_AV17  POWER  = GND
  AV18  MJA0_CS_L1  OUT  = M_J_CPU1_SA_CS_N<1>
  AV19  VDDCR_SOC_AV19  POWER  = PVDDCR_SOC_P1
  AV20  MIA1_CS_L0  OUT  = NC
  AV21  MIA0_CS_L1  OUT  = M_I_CPU1_SA_CS_N<1>
  AV22  VDDCR_SOC_AV22  POWER  = PVDDCR_SOC_P1
  AV23  VSS_AV23  POWER  = GND
  AV24  VDDCR_SOC_AV24  POWER  = PVDDCR_SOC_P1
  AV25  VSS_AV25  POWER  = GND
  AV26  VDDCR_SOC_AV26  POWER  = PVDDCR_SOC_P1
  AV27  VSS_AV27  POWER  = GND
  AV28  VDDCR_SOC_AV28  POWER  = PVDDCR_SOC_P1
  AV29  VSS_AV29  POWER  = GND
  AV30  VDDCR_SOC_AV30  POWER  = PVDDCR_SOC_P1
  AV31  VSS_AV31  POWER  = GND
  AV32  VDDCR_SOC_AV32  POWER  = PVDDCR_SOC_P1
  AV33  VSS_AV33  POWER  = GND
  AV34  VDDCR_SOC_AV34  POWER  = PVDDCR_SOC_P1
  AV35  VSS_AV35  POWER  = GND
  AV36  VDDCR_SOC_AV36  POWER  = PVDDCR_SOC_P1
  AV37  VSS_AV37  POWER  = GND
  AV39  VDDCR_SOC_AV39  POWER  = PVDDCR_SOC_P1
  AV40  VSS_AV40  POWER  = GND
  AV41  VDDCR_SOC_AV41  POWER  = PVDDCR_SOC_P1
  AV42  VSS_AV42  POWER  = GND
  AV43  VDDCR_SOC_AV43  POWER  = PVDDCR_SOC_P1
  AV44  VSS_AV44  POWER  = GND
  AV45  VDDCR_SOC_AV45  POWER  = PVDDCR_SOC_P1
  AV46  VSS_AV46  POWER  = GND
  AV47  VDDCR_SOC_AV47  POWER  = PVDDCR_SOC_P1
  AV48  VSS_AV48  POWER  = GND
  AV49  VDD_18_S5_AV49  POWER  = PVDD18_S5_P1
  AV50  VSS_AV50  POWER  = GND
  AV51  VDD_18_S5_AV51  POWER  = PVDD18_S5_P1
  AV52  VSS_AV52  POWER  = GND
  AV53  VDD_18_S5_AV53  POWER  = PVDD18_S5_P1
  AV54  VSS_AV54  POWER  = GND
  AV55  MCA1_CS_L1  OUT  = NC
  AV56  MCA0_CS_L0  OUT  = M_C_CPU1_SA_CS_N<0>
  AV57  VDDIO_AV57  POWER  = PVDDIO_P1
  AV58  MDA1_CS_L1  OUT  = NC
  AV59  VSS_AV59  POWER  = GND
  AV60  MDA0_CS_L0  OUT  = M_D_CPU1_SA_CS_N<0>
  AV61  VSS_AV61  POWER  = GND
  AV62  MBA1_CS_L1  OUT  = NC
  AV63  MBA0_CS_L0  OUT  = M_B_CPU1_SA_CS_N<0>
  AV64  VDDIO_AV64  POWER  = PVDDIO_P1
  AV65  MFA1_CS_L1  OUT  = NC
  AV66  VSS_AV66  POWER  = GND
